# TIMECARD (Time Appliance Project (Time Card)) — schematic netlist excerpt (pin names and nets, part order shuffled) for the footprints in the layout excerpt that follows; sources: Cadence DE-HDL packaged netlist, KiCad conversion of R4006-B0001-02_R01.brd

C1  CAPACITOR  0.1UF 25V 10%  pkg SMC_0402R_H022  page 16 : \1\ = XP3R3V_FPGA ; \2\ = SG
R246  RESISTOR  5.1KOHM 1%  pkg SMC_0402R_H016  page 29 : \1\ = UNNAMED_523_CAPACITOR_I7_1 ; \2\ = SG

(kicad_pcb
	(version 20260206)
	(generator "pcbnew")
	(generator_version "10.0")
	(general
		(thickness 1.6)
		(legacy_teardrops no)
	)
	(paper "A4")
	(title_block
		(title "timecard-production-celestica-r4006 — R4006-B0001-02_R01.brd")
		(comment 1 "Time Appliance Project (Time Card) / footprints 708-709 of 1113")
	)
	(layers
		(0 "F.Cu" signal "TOP")
		(4 "In1.Cu" signal "L02_GND1")
		(6 "In2.Cu" signal "L03_SIG1")
		(8 "In3.Cu" signal "L04_GND2")
		(10 "In4.Cu" signal "L05_VCC1")
		(12 "In5.Cu" signal "L06_VCC2")
		(14 "In6.Cu" signal "L07_GND3")
		(16 "In7.Cu" signal "L08_SIG2")
		(18 "In8.Cu" signal "L09_GND4")
		(2 "B.Cu" signal "BOTTOM")
		(9 "F.Adhes" user "F.Adhesive")
		(11 "B.Adhes" user "B.Adhesive")
		(13 "F.Paste" user "Package Geometry/Pastemask Top")
		(15 "B.Paste" user "Package Geometry/Pastemask Bottom")
		(5 "F.SilkS" user "Ref Des/Silkscreen Top")
		(7 "B.SilkS" user "Ref Des/Silkscreen Bottom")
		(1 "F.Mask" user "Board Geometry/Soldermask Top")
		(3 "B.Mask" user "Board Geometry/Soldermask Bottom")
		(17 "Dwgs.User" user "User.Drawings")
		(19 "Cmts.User" user "User.Comments")
		(21 "Eco1.User" user "User.Eco1")
		(23 "Eco2.User" user "User.Eco2")
		(25 "Edge.Cuts" user "Board Geometry/Outline")
		(27 "Margin" user)
		(31 "F.CrtYd" user "Package Geometry/Place Bound Top")
		(29 "B.CrtYd" user "Package Geometry/Place Bound Bottom")
		(35 "F.Fab" user "Ref Des/Assembly Top")
		(33 "B.Fab" user "Ref Des/Assembly Bottom")
	)
	(footprint ""
		(layer "B.Cu")
		(at 21.844 -20.6248 -90)
		(property "Reference" "C1"
			(at 0.9398 -1.10363 270)
			(unlocked yes)
			(layer "B.SilkS")
			(effects
				(font
					(size 0.7874 0.5842)
					(thickness 0.1524)
				)
				(justify mirror)
			)
		)
		(property "Value" "VAL*"
			(at -0.0762 2.067306 270)
			(unlocked yes)
			(layer "B.Fab")
			(hide yes)
			(effects
				(font
					(size 0.7874 0.5842)
					(thickness 0.1524)
				)
				(justify mirror)
			)
		)
		(property "Device Type" "CAPACITOR-G105-0B104-EK,0.1UF,A"
			(at -0.0508 1.127506 270)
			(unlocked yes)
			(layer "B.Fab")
			(hide yes)
			(effects
				(font
					(size 0.7874 0.5842)
					(thickness 0.1524)
				)
				(justify mirror)
			)
		)
		(property "User Part Number" "PARTNUM*"
			(at -0.1016 4.023106 270)
			(unlocked yes)
			(layer "Cmts.User")
			(hide yes)
			(effects
				(font
					(size 0.7874 0.5842)
					(thickness 0.1524)
				)
				(justify mirror)
			)
		)
		(property "Tolerance" "TOL*"
			(at -0.0762 3.032506 270)
			(unlocked yes)
			(layer "Cmts.User")
			(hide yes)
			(effects
				(font
					(size 0.7874 0.5842)
					(thickness 0.1524)
				)
				(justify mirror)
			)
		)
		(duplicate_pad_numbers_are_jumpers no)
		(fp_line
			(start -1.143 0.5588)
			(end -1.143 -0.5588)
			(stroke
				(width 0.1)
				(type default)
			)
			(layer "B.SilkS")
		)
		(fp_line
			(start 1.143 0.5588)
			(end -1.143 0.5588)
			(stroke
				(width 0.1)
				(type default)
			)
			(layer "B.SilkS")
		)
		(fp_line
			(start -1.143 -0.5588)
			(end 1.143 -0.5588)
			(stroke
				(width 0.1)
				(type default)
			)
			(layer "B.SilkS")
		)
		(fp_line
			(start 1.143 -0.5588)
			(end 1.143 0.5588)
			(stroke
				(width 0.1)
				(type default)
			)
			(layer "B.SilkS")
		)
		(fp_rect
			(start 1.143 0.5588)
			(end -1.143 -0.5588)
			(stroke
				(width 0)
				(type default)
			)
			(fill no)
			(layer "B.CrtYd")
		)
		(fp_line
			(start -0.508 0.3048)
			(end -0.508 -0.3048)
			(stroke
				(width 0.1)
				(type default)
			)
			(layer "B.Fab")
		)
		(fp_line
			(start 0.508 0.3048)
			(end -0.508 0.3048)
			(stroke
				(width 0.1)
				(type default)
			)
			(layer "B.Fab")
		)
		(fp_line
			(start -0.508 -0.3048)
			(end 0.508 -0.3048)
			(stroke
				(width 0.1)
				(type default)
			)
			(layer "B.Fab")
		)
		(fp_line
			(start 0.508 -0.3048)
			(end 0.508 0.3048)
			(stroke
				(width 0.1)
				(type default)
			)
			(layer "B.Fab")
		)
		(pad "1" smd rect
			(at 0.5334 0 90)
			(size 0.7112 0.6096)
			(layers "B.Cu" "B.Mask" "B.Paste")
			(net "XP3R3V_FPGA")
		)
		(pad "2" smd rect
			(at -0.5334 0 90)
			(size 0.7112 0.6096)
			(layers "B.Cu" "B.Mask" "B.Paste")
			(net "SG")
		)
		(zone
			(layer "B.Cu")
			(hatch none 0.5)
			(connect_pads
				(clearance 0)
			)
			(min_thickness 0.25)
			(keepout
				(tracks not_allowed)
				(vias allowed)
				(pads allowed)
				(copperpour not_allowed)
				(footprints allowed)
			)
			(placement
				(enabled no)
				(sheetname "")
			)
			(fill
				(thermal_gap 0.5)
				(thermal_bridge_width 0.5)
				(island_removal_mode 0)
			)
			(polygon
				(pts
					(xy 21.5392 -20.5486) (xy 22.1488 -20.5486) (xy 22.1488 -20.701) (xy 21.5392 -20.701)
				)
			)
		)
		(zone
			(layer "B.Cu")
			(hatch none 0.5)
			(connect_pads
				(clearance 0)
			)
			(min_thickness 0.25)
			(keepout
				(tracks allowed)
				(vias not_allowed)
				(pads allowed)
				(copperpour not_allowed)
				(footprints allowed)
			)
			(placement
				(enabled no)
				(sheetname "")
			)
			(fill
				(thermal_gap 0.5)
				(thermal_bridge_width 0.5)
				(island_removal_mode 0)
			)
			(polygon
				(pts
					(xy 21.5392 -20.5486) (xy 22.1488 -20.5486) (xy 22.1488 -20.701) (xy 21.5392 -20.701)
				)
			)
		)
	)
	(footprint ""
		(layer "B.Cu")
		(at 141.097 -59.563 -90)
		(property "Reference" "R246"
			(at -3.175 0.16637 270)
			(unlocked yes)
			(layer "B.SilkS")
			(effects
				(font
					(size 0.7874 0.5842)
					(thickness 0.1524)
				)
				(justify mirror)
			)
		)
		(property "Value" "VAL*"
			(at -0.02032 2.13233 270)
			(unlocked yes)
			(layer "B.Fab")
			(hide yes)
			(effects
				(font
					(size 0.7874 0.5842)
					(thickness 0.1524)
				)
				(justify mirror)
			)
		)
		(property "Device Type" "RESISTOR-A155-05101-DL,5.1KOHMA"
			(at -0.008382 1.210564 270)
			(unlocked yes)
			(layer "B.Fab")
			(hide yes)
			(effects
				(font
					(size 0.7874 0.5842)
					(thickness 0.1524)
				)
				(justify mirror)
			)
		)
		(property "User Part Number" "PARTNUM*"
			(at -0.02032 4.024884 270)
			(unlocked yes)
			(layer "Cmts.User")
			(hide yes)
			(effects
				(font
					(size 0.7874 0.5842)
					(thickness 0.1524)
				)
				(justify mirror)
			)
		)
		(property "Tolerance" "TOL*"
			(at -0.044704 3.05435 270)
			(unlocked yes)
			(layer "Cmts.User")
			(hide yes)
			(effects
				(font
					(size 0.7874 0.5842)
					(thickness 0.1524)
				)
				(justify mirror)
			)
		)
		(duplicate_pad_numbers_are_jumpers no)
		(fp_line
			(start -1.143 0.5588)
			(end -1.143 -0.5588)
			(stroke
				(width 0.1)
				(type default)
			)
			(layer "B.SilkS")
		)
		(fp_line
			(start 1.143 0.5588)
			(end -1.143 0.5588)
			(stroke
				(width 0.1)
				(type default)
			)
			(layer "B.SilkS")
		)
		(fp_line
			(start -1.143 -0.5588)
			(end 1.143 -0.5588)
			(stroke
				(width 0.1)
				(type default)
			)
			(layer "B.SilkS")
		)
		(fp_line
			(start 1.143 -0.5588)
			(end 1.143 0.5588)
			(stroke
				(width 0.1)
				(type default)
			)
			(layer "B.SilkS")
		)
		(fp_rect
			(start 1.143 0.5588)
			(end -1.143 -0.5588)
			(stroke
				(width 0)
				(type default)
			)
			(fill no)
			(layer "B.CrtYd")
		)
		(fp_line
			(start -0.508 0.3048)
			(end -0.508 -0.3048)
			(stroke
				(width 0.1)
				(type default)
			)
			(layer "B.Fab")
		)
		(fp_line
			(start 0.508 0.3048)
			(end -0.508 0.3048)
			(stroke
				(width 0.1)
				(type default)
			)
			(layer "B.Fab")
		)
		(fp_line
			(start -0.508 -0.3048)
			(end 0.508 -0.3048)
			(stroke
				(width 0.1)
				(type default)
			)
			(layer "B.Fab")
		)
		(fp_line
			(start 0.508 -0.3048)
			(end 0.508 0.3048)
			(stroke
				(width 0.1)
				(type default)
			)
			(layer "B.Fab")
		)
		(pad "1" smd rect
			(at 0.5334 0 90)
			(size 0.7112 0.6096)
			(layers "B.Cu" "B.Mask" "B.Paste")
			(net "UNNAMED_523_CAPACITOR_I7_1")
		)
		(pad "2" smd rect
			(at -0.5334 0 90)
			(size 0.7112 0.6096)
			(layers "B.Cu" "B.Mask" "B.Paste")
			(net "SG")
		)
		(zone
			(layer "B.Cu")
			(hatch none 0.5)
			(connect_pads
				(clearance 0)
			)
			(min_thickness 0.25)
			(keepout
				(tracks allowed)
				(vias not_allowed)
				(pads allowed)
				(copperpour not_allowed)
				(footprints allowed)
			)
			(placement
				(enabled no)
				(sheetname "")
			)
			(fill
				(thermal_gap 0.5)
				(thermal_bridge_width 0.5)
				(island_removal_mode 0)
			)
			(polygon
				(pts
					(xy 140.7922 -59.4868) (xy 141.4018 -59.4868) (xy 141.4018 -59.6392) (xy 140.7922 -59.6392)
				)
			)
		)
	)
)
